# T6G (Grand Teton) — schematic netlist excerpt (pin names and nets, part order shuffled) for the footprints in the layout excerpt that follows; sources: Cadence DE-HDL packaged netlist, KiCad conversion of 04192023_DAF0TMB3IC0_F0TG_MB_C_brd_V02_OCP.brd

C367  Q_CAP  100UF 4V 20% X6S  pkg C0805  page 345 : A = P1V8_CPU1_RT2_1A ; B = GND
R3495  Q_RES  100K 1% EMPTY  pkg 0402LF  page 129 : A = GPU_FPGA_EROT_RECOV_BUF_R_N ; B = GND
PR4014  Q_RES  49.9 1% CHIP  pkg 0603LF  page 152 : A = P12V_AUX ; B = P12V_SCM_AVIN_PD

(kicad_pcb
	(version 20260206)
	(generator "pcbnew")
	(generator_version "10.0")
	(general
		(thickness 1.6)
		(legacy_teardrops no)
	)
	(paper "A4")
	(title_block
		(title "04192023_DAF0TMB3IC0_F0TG_MB_C_brd_V02_OCP.brd")
		(comment 1 "Grand Teton / footprints 4915-4917 of 8354")
	)
	(layers
		(0 "F.Cu" signal "TOP")
		(4 "In1.Cu" signal "GND")
		(6 "In2.Cu" signal "IN1")
		(8 "In3.Cu" signal "GND1")
		(10 "In4.Cu" signal "IN2")
		(12 "In5.Cu" signal "GND2")
		(14 "In6.Cu" signal "IN3")
		(16 "In7.Cu" signal "GND3")
		(18 "In8.Cu" signal "VCC")
		(20 "In9.Cu" signal "VCC1")
		(22 "In10.Cu" signal "GND4")
		(24 "In11.Cu" signal "IN4")
		(26 "In12.Cu" signal "GND5")
		(28 "In13.Cu" signal "IN5")
		(30 "In14.Cu" signal "GND6")
		(32 "In15.Cu" signal "IN6")
		(34 "In16.Cu" signal "GND7")
		(2 "B.Cu" signal "BOTTOM")
		(9 "F.Adhes" user "F.Adhesive")
		(11 "B.Adhes" user "B.Adhesive")
		(13 "F.Paste" user "Package Geometry/Pastemask Top")
		(15 "B.Paste" user "Package Geometry/Pastemask Bottom")
		(5 "F.SilkS" user "Ref Des/Silkscreen Top")
		(7 "B.SilkS" user "Ref Des/Silkscreen Bottom")
		(1 "F.Mask" user "Board Geometry/Soldermask Top")
		(3 "B.Mask" user "Board Geometry/Soldermask Bottom")
		(17 "Dwgs.User" user "User.Drawings")
		(19 "Cmts.User" user "User.Comments")
		(21 "Eco1.User" user "User.Eco1")
		(23 "Eco2.User" user "User.Eco2")
		(25 "Edge.Cuts" user "Board Geometry/Outline")
		(27 "Margin" user)
		(31 "F.CrtYd" user "Package Geometry/Place Bound Top")
		(29 "B.CrtYd" user "Package Geometry/Place Bound Bottom")
		(35 "F.Fab" user "Ref Des/Assembly Top")
		(33 "B.Fab" user "Ref Des/Assembly Bottom")
	)
	(footprint ""
		(layer "F.Cu")
		(at 174.635922 -24.601932)
		(property "Reference" "PR4014"
			(at 0 0 0)
			(layer "F.SilkS")
			(hide yes)
			(effects
				(font
					(size 1.27 1.27)
				)
			)
		)
		(property "Value" ""
			(at 0 0 0)
			(layer "F.Fab")
			(effects
				(font
					(size 1.27 1.27)
				)
			)
		)
		(duplicate_pad_numbers_are_jumpers no)
		(fp_line
			(start -1.2954 -0.5842)
			(end 1.2954 -0.5842)
			(stroke
				(width 0.1524)
				(type default)
			)
			(layer "F.SilkS")
		)
		(fp_line
			(start -1.2954 0.5842)
			(end -1.2954 -0.5842)
			(stroke
				(width 0.1524)
				(type default)
			)
			(layer "F.SilkS")
		)
		(fp_line
			(start 1.2954 -0.5842)
			(end 1.2954 0.5842)
			(stroke
				(width 0.1524)
				(type default)
			)
			(layer "F.SilkS")
		)
		(fp_line
			(start 1.2954 0.5842)
			(end -1.2954 0.5842)
			(stroke
				(width 0.1524)
				(type default)
			)
			(layer "F.SilkS")
		)
		(fp_line
			(start -1.1938 -0.406654)
			(end -0.8636 -0.406654)
			(stroke
				(width 0.1)
				(type default)
			)
			(layer "F.Fab")
		)
		(fp_line
			(start -1.1938 0.4064)
			(end -1.1938 -0.406654)
			(stroke
				(width 0.1)
				(type default)
			)
			(layer "F.Fab")
		)
		(fp_line
			(start -0.8636 -0.4572)
			(end 0.8636 -0.4572)
			(stroke
				(width 0.1)
				(type default)
			)
			(layer "F.Fab")
		)
		(fp_line
			(start -0.8636 -0.406654)
			(end -0.8636 -0.4572)
			(stroke
				(width 0.1)
				(type default)
			)
			(layer "F.Fab")
		)
		(fp_line
			(start -0.8636 0.4064)
			(end -1.1938 0.4064)
			(stroke
				(width 0.1)
				(type default)
			)
			(layer "F.Fab")
		)
		(fp_line
			(start -0.8636 0.4318)
			(end -0.8636 0.4064)
			(stroke
				(width 0.1)
				(type default)
			)
			(layer "F.Fab")
		)
		(fp_line
			(start -0.8636 0.4572)
			(end -0.8636 0.4318)
			(stroke
				(width 0.1)
				(type default)
			)
			(layer "F.Fab")
		)
		(fp_line
			(start 0.8636 -0.4572)
			(end 0.8636 -0.406654)
			(stroke
				(width 0.1)
				(type default)
			)
			(layer "F.Fab")
		)
		(fp_line
			(start 0.8636 -0.406654)
			(end 1.1938 -0.406654)
			(stroke
				(width 0.1)
				(type default)
			)
			(layer "F.Fab")
		)
		(fp_line
			(start 0.8636 0.4064)
			(end 0.8636 0.4572)
			(stroke
				(width 0.1)
				(type default)
			)
			(layer "F.Fab")
		)
		(fp_line
			(start 0.8636 0.4572)
			(end -0.8636 0.4572)
			(stroke
				(width 0.1)
				(type default)
			)
			(layer "F.Fab")
		)
		(fp_line
			(start 1.1938 -0.406654)
			(end 1.1938 0.4064)
			(stroke
				(width 0.1)
				(type default)
			)
			(layer "F.Fab")
		)
		(fp_line
			(start 1.1938 0.4064)
			(end 0.8636 0.4064)
			(stroke
				(width 0.1)
				(type default)
			)
			(layer "F.Fab")
		)
		(pad "1" smd rect
			(at -0.7366 0 270)
			(size 0.7112 0.8128)
			(layers "F.Cu" "F.Mask" "F.Paste")
			(net "P12V_AUX")
		)
		(pad "2" smd rect
			(at 0.7366 0 270)
			(size 0.7112 0.8128)
			(layers "F.Cu" "F.Mask" "F.Paste")
			(net "P12V_SCM_AVIN_PD")
		)
	)
	(footprint ""
		(layer "F.Cu")
		(at 170.2308 -386.3848)
		(property "Reference" "C367"
			(at 0 0 0)
			(layer "F.SilkS")
			(hide yes)
			(effects
				(font
					(size 1.27 1.27)
				)
			)
		)
		(property "Value" ""
			(at 0 0 0)
			(layer "F.Fab")
			(effects
				(font
					(size 1.27 1.27)
				)
			)
		)
		(duplicate_pad_numbers_are_jumpers no)
		(fp_line
			(start -1.524 -0.762)
			(end 1.524 -0.762)
			(stroke
				(width 0.1524)
				(type default)
			)
			(layer "F.SilkS")
		)
		(fp_line
			(start -1.524 0.762)
			(end -1.524 -0.762)
			(stroke
				(width 0.1524)
				(type default)
			)
			(layer "F.SilkS")
		)
		(fp_line
			(start 1.524 -0.762)
			(end 1.524 0.762)
			(stroke
				(width 0.1524)
				(type default)
			)
			(layer "F.SilkS")
		)
		(fp_line
			(start 1.524 0.762)
			(end -1.524 0.762)
			(stroke
				(width 0.1524)
				(type default)
			)
			(layer "F.SilkS")
		)
		(fp_line
			(start -1.1049 -0.724916)
			(end -1.1049 0.724916)
			(stroke
				(width 0.1)
				(type default)
			)
			(layer "F.Fab")
		)
		(fp_line
			(start -1.1049 0.724916)
			(end 1.1049 0.724916)
			(stroke
				(width 0.1)
				(type default)
			)
			(layer "F.Fab")
		)
		(fp_line
			(start 1.1049 -0.724916)
			(end -1.1049 -0.724916)
			(stroke
				(width 0.1)
				(type default)
			)
			(layer "F.Fab")
		)
		(fp_line
			(start 1.1049 0.724916)
			(end 1.1049 -0.724916)
			(stroke
				(width 0.1)
				(type default)
			)
			(layer "F.Fab")
		)
		(pad "1" smd rect
			(at -0.889 0 180)
			(size 1.016 1.27)
			(layers "F.Cu" "F.Mask" "F.Paste")
			(net "P1V8_CPU1_RT2_1A")
		)
		(pad "2" smd rect
			(at 0.889 0 180)
			(size 1.016 1.27)
			(layers "F.Cu" "F.Mask" "F.Paste")
			(net "GND")
		)
	)
	(footprint ""
		(layer "F.Cu")
		(at 120.396 -435.483)
		(property "Reference" "R3495"
			(at 0 0 0)
			(layer "F.SilkS")
			(hide yes)
			(effects
				(font
					(size 1.27 1.27)
				)
			)
		)
		(property "Value" ""
			(at 0 0 0)
			(layer "F.Fab")
			(effects
				(font
					(size 1.27 1.27)
				)
			)
		)
		(duplicate_pad_numbers_are_jumpers no)
		(fp_line
			(start -0.7874 -0.4064)
			(end 0.7874 -0.4064)
			(stroke
				(width 0.1524)
				(type default)
			)
			(layer "F.SilkS")
		)
		(fp_line
			(start -0.7874 0.4064)
			(end -0.7874 -0.4064)
			(stroke
				(width 0.1524)
				(type default)
			)
			(layer "F.SilkS")
		)
		(fp_line
			(start 0.7874 -0.4064)
			(end 0.7874 0.4064)
			(stroke
				(width 0.1524)
				(type default)
			)
			(layer "F.SilkS")
		)
		(fp_line
			(start 0.7874 0.4064)
			(end -0.7874 0.4064)
			(stroke
				(width 0.1524)
				(type default)
			)
			(layer "F.SilkS")
		)
		(fp_line
			(start -0.67945 -0.305054)
			(end -0.12065 -0.305054)
			(stroke
				(width 0.1)
				(type default)
			)
			(layer "F.Fab")
		)
		(fp_line
			(start -0.67945 0.3048)
			(end -0.67945 -0.305054)
			(stroke
				(width 0.1)
				(type default)
			)
			(layer "F.Fab")
		)
		(fp_line
			(start -0.12065 -0.305054)
			(end -0.12065 -0.2794)
			(stroke
				(width 0.1)
				(type default)
			)
			(layer "F.Fab")
		)
		(fp_line
			(start -0.12065 -0.2794)
			(end 0.12065 -0.2794)
			(stroke
				(width 0.1)
				(type default)
			)
			(layer "F.Fab")
		)
		(fp_line
			(start -0.12065 0.2794)
			(end -0.12065 0.3048)
			(stroke
				(width 0.1)
				(type default)
			)
			(layer "F.Fab")
		)
		(fp_line
			(start -0.12065 0.3048)
			(end -0.67945 0.3048)
			(stroke
				(width 0.1)
				(type default)
			)
			(layer "F.Fab")
		)
		(fp_line
			(start 0.120396 0.2794)
			(end -0.12065 0.2794)
			(stroke
				(width 0.1)
				(type default)
			)
			(layer "F.Fab")
		)
		(fp_line
			(start 0.120396 0.3048)
			(end 0.120396 0.2794)
			(stroke
				(width 0.1)
				(type default)
			)
			(layer "F.Fab")
		)
		(fp_line
			(start 0.12065 -0.3048)
			(end 0.67945 -0.3048)
			(stroke
				(width 0.1)
				(type default)
			)
			(layer "F.Fab")
		)
		(fp_line
			(start 0.12065 -0.2794)
			(end 0.12065 -0.3048)
			(stroke
				(width 0.1)
				(type default)
			)
			(layer "F.Fab")
		)
		(fp_line
			(start 0.67945 -0.3048)
			(end 0.67945 0.3048)
			(stroke
				(width 0.1)
				(type default)
			)
			(layer "F.Fab")
		)
		(fp_line
			(start 0.67945 0.3048)
			(end 0.120396 0.3048)
			(stroke
				(width 0.1)
				(type default)
			)
			(layer "F.Fab")
		)
		(pad "1" smd circle
			(at -0.40005 0)
			(size 0 0)
			(layers "F.Cu" "F.Mask" "F.Paste")
			(net "GPU_FPGA_EROT_RECOV_BUF_R_N")
		)
		(pad "2" smd circle
			(at 0.40005 0)
			(size 0 0)
			(layers "F.Cu" "F.Mask" "F.Paste")
			(net "GND")
		)
	)
)
